FILE_TYPE=LIBRARY_PARTS;
primitive 'TTL1G126_a','TTL1G126_A_SOT';
  pin
    'OE':
      PIN_NUMBER='(1)';
      INPUT_LOAD='(-0.01,0.01)';
    'A':
      PIN_NUMBER='(2)';
      INPUT_LOAD='(-0.01,0.01)';
    'Y':
      PIN_NUMBER='(4)';
      OUTPUT_LOAD='(1.0,-1.0)';
  end_pin;
  body
    POWER_PINS='(VCC:5)';
    POWER_PINS='(GND:3)';
    CLASS='IC';
    PART_NAME='TTL1G126_A';
    PHYS_DES_PREFIX='U';
  end_body;
end_primitive;
END.
